(kicad_pcb
	(version 20260206)
	(generator "pcbnew")
	(generator_version "10.0")
	(general
		(thickness 1.6)
		(legacy_teardrops no)
	)
	(paper "A4")
	(title_block
		(title "01162023_DA0F0TEBIF0_F0T_Expander_BD_F_brd_V02_OCP.brd")
		(comment 1 "Grand Teton / footprint 5622 of 9728 (PEX2), pads 595-713 of 2397")
	)
	(layers
		(0 "F.Cu" signal "TOP")
		(4 "In1.Cu" signal "GND")
		(6 "In2.Cu" signal "VCC")
		(8 "In3.Cu" signal "VCC1")
		(10 "In4.Cu" signal "GND1")
		(12 "In5.Cu" signal "IN1")
		(14 "In6.Cu" signal "GND2")
		(16 "In7.Cu" signal "IN2")
		(18 "In8.Cu" signal "GND3")
		(20 "In9.Cu" signal "IN3")
		(22 "In10.Cu" signal "GND4")
		(24 "In11.Cu" signal "IN4")
		(26 "In12.Cu" signal "GND5")
		(28 "In13.Cu" signal "IN5")
		(30 "In14.Cu" signal "GND6")
		(32 "In15.Cu" signal "IN6")
		(34 "In16.Cu" signal "GND7")
		(2 "B.Cu" signal "BOTTOM")
		(9 "F.Adhes" user "F.Adhesive")
		(11 "B.Adhes" user "B.Adhesive")
		(13 "F.Paste" user "Package Geometry/Pastemask Top")
		(15 "B.Paste" user "Package Geometry/Pastemask Bottom")
		(5 "F.SilkS" user "Ref Des/Silkscreen Top")
		(7 "B.SilkS" user "Ref Des/Silkscreen Bottom")
		(1 "F.Mask" user "Board Geometry/Soldermask Top")
		(3 "B.Mask" user "Board Geometry/Soldermask Bottom")
		(17 "Dwgs.User" user "User.Drawings")
		(19 "Cmts.User" user "User.Comments")
		(21 "Eco1.User" user "User.Eco1")
		(23 "Eco2.User" user "User.Eco2")
		(25 "Edge.Cuts" user "Board Geometry/Outline")
		(27 "Margin" user)
		(31 "F.CrtYd" user "Package Geometry/Place Bound Top")
		(29 "B.CrtYd" user "Package Geometry/Place Bound Bottom")
		(35 "F.Fab" user "Ref Des/Assembly Top")
		(33 "B.Fab" user "Ref Des/Assembly Bottom")
	)
	(footprint ""
		(layer "F.Cu")
		(at 291.84981 -295.89984)
		(property "Reference" "PEX2"
			(at -3.35153 35.56762 0)
			(unlocked yes)
			(layer "F.SilkS")
			(effects
				(font
					(size 2.032 1.524)
					(thickness 0.1524)
				)
				(justify left)
			)
		)
		(property "Value" ""
			(at 0 0 0)
			(layer "F.Fab")
			(effects
				(font
					(size 1.27 1.27)
				)
			)
		)
		(duplicate_pad_numbers_are_jumpers no)
		(pad "AM9" smd circle
			(at -15.200122 6.649974)
			(size 0.4572 0.4572)
			(layers "F.Cu" "F.Mask" "F.Paste")
			(net "Net_1445")
		)
		(pad "AM10" smd circle
			(at -14.249908 6.649974)
			(size 0.4572 0.4572)
			(layers "F.Cu" "F.Mask" "F.Paste")
			(net "GND")
		)
		(pad "AM11" smd circle
			(at -13.299948 6.649974)
			(size 0.4572 0.4572)
			(layers "F.Cu" "F.Mask" "F.Paste")
			(net "GND")
		)
		(pad "AM12" smd circle
			(at -12.349988 6.649974)
			(size 0.4572 0.4572)
			(layers "F.Cu" "F.Mask" "F.Paste")
			(net "TP_PEX2_VDDQ_EFUSE")
		)
		(pad "AM13" smd circle
			(at -11.400028 6.649974)
			(size 0.4572 0.4572)
			(layers "F.Cu" "F.Mask" "F.Paste")
			(net "GND")
		)
		(pad "AM14" smd circle
			(at -10.450068 6.649974)
			(size 0.4572 0.4572)
			(layers "F.Cu" "F.Mask" "F.Paste")
			(net "P1V8_VDDA_PEX2")
		)
		(pad "AM15" smd circle
			(at -9.500108 6.649974)
			(size 0.4572 0.4572)
			(layers "F.Cu" "F.Mask" "F.Paste")
			(net "GND")
		)
		(pad "AM16" smd circle
			(at -8.549894 6.649974)
			(size 0.4572 0.4572)
			(layers "F.Cu" "F.Mask" "F.Paste")
			(net "P1V25_PEX2")
		)
		(pad "AM17" smd circle
			(at -7.599934 6.649974)
			(size 0.4572 0.4572)
			(layers "F.Cu" "F.Mask" "F.Paste")
			(net "P1V25_PEX2")
		)
		(pad "AM18" smd circle
			(at -6.649974 6.649974)
			(size 0.4572 0.4572)
			(layers "F.Cu" "F.Mask" "F.Paste")
			(net "P1V25_PEX2")
		)
		(pad "AM19" smd circle
			(at -5.700014 6.649974)
			(size 0.4572 0.4572)
			(layers "F.Cu" "F.Mask" "F.Paste")
			(net "P1V25_PEX2")
		)
		(pad "AM20" smd circle
			(at -4.750054 6.649974)
			(size 0.4572 0.4572)
			(layers "F.Cu" "F.Mask" "F.Paste")
			(net "P1V25_PEX2")
		)
		(pad "AM21" smd circle
			(at -3.800094 6.649974)
			(size 0.4572 0.4572)
			(layers "F.Cu" "F.Mask" "F.Paste")
			(net "P1V25_PEX2")
		)
		(pad "AM22" smd circle
			(at -2.84988 6.649974)
			(size 0.4572 0.4572)
			(layers "F.Cu" "F.Mask" "F.Paste")
			(net "P1V25_PEX2")
		)
		(pad "AM23" smd circle
			(at -1.89992 6.649974)
			(size 0.4572 0.4572)
			(layers "F.Cu" "F.Mask" "F.Paste")
			(net "P1V25_PEX2")
		)
		(pad "AM24" smd circle
			(at -0.94996 6.649974)
			(size 0.4572 0.4572)
			(layers "F.Cu" "F.Mask" "F.Paste")
			(net "P1V25_PEX2")
		)
		(pad "AM25" smd circle
			(at 0 6.649974)
			(size 0.4572 0.4572)
			(layers "F.Cu" "F.Mask" "F.Paste")
			(net "P1V25_PEX2")
		)
		(pad "AM26" smd circle
			(at 0.94996 6.649974)
			(size 0.4572 0.4572)
			(layers "F.Cu" "F.Mask" "F.Paste")
			(net "P1V25_PEX2")
		)
		(pad "AM27" smd circle
			(at 1.89992 6.649974)
			(size 0.4572 0.4572)
			(layers "F.Cu" "F.Mask" "F.Paste")
			(net "P1V25_PEX2")
		)
		(pad "AM28" smd circle
			(at 2.84988 6.649974)
			(size 0.4572 0.4572)
			(layers "F.Cu" "F.Mask" "F.Paste")
			(net "P1V25_PEX2")
		)
		(pad "AM29" smd circle
			(at 3.800094 6.649974)
			(size 0.4572 0.4572)
			(layers "F.Cu" "F.Mask" "F.Paste")
			(net "P1V25_PEX2")
		)
		(pad "AM30" smd circle
			(at 4.750054 6.649974)
			(size 0.4572 0.4572)
			(layers "F.Cu" "F.Mask" "F.Paste")
			(net "P1V25_PEX2")
		)
		(pad "AM31" smd circle
			(at 5.700014 6.649974)
			(size 0.4572 0.4572)
			(layers "F.Cu" "F.Mask" "F.Paste")
			(net "P1V25_PEX2")
		)
		(pad "AM32" smd circle
			(at 6.649974 6.649974)
			(size 0.4572 0.4572)
			(layers "F.Cu" "F.Mask" "F.Paste")
			(net "P1V25_PEX2")
		)
		(pad "AM33" smd circle
			(at 7.599934 6.649974)
			(size 0.4572 0.4572)
			(layers "F.Cu" "F.Mask" "F.Paste")
			(net "P1V25_PEX2")
		)
		(pad "AM34" smd circle
			(at 8.549894 6.649974)
			(size 0.4572 0.4572)
			(layers "F.Cu" "F.Mask" "F.Paste")
			(net "GND")
		)
		(pad "AM35" smd circle
			(at 9.500108 6.649974)
			(size 0.4572 0.4572)
			(layers "F.Cu" "F.Mask" "F.Paste")
			(net "P1V8_PEX")
		)
		(pad "AM36" smd circle
			(at 10.450068 6.649974)
			(size 0.4572 0.4572)
			(layers "F.Cu" "F.Mask" "F.Paste")
			(net "GND")
		)
		(pad "AM37" smd circle
			(at 11.400028 6.649974)
			(size 0.4572 0.4572)
			(layers "F.Cu" "F.Mask" "F.Paste")
			(net "GND")
		)
		(pad "AM38" smd circle
			(at 12.349988 6.649974)
			(size 0.4572 0.4572)
			(layers "F.Cu" "F.Mask" "F.Paste")
			(net "Net_5326")
		)
		(pad "AM39" smd circle
			(at 13.299948 6.649974)
			(size 0.4572 0.4572)
			(layers "F.Cu" "F.Mask" "F.Paste")
			(net "Net_5369")
		)
		(pad "AM40" smd circle
			(at 14.249908 6.649974)
			(size 0.4572 0.4572)
			(layers "F.Cu" "F.Mask" "F.Paste")
			(net "GND")
		)
		(pad "AM41" smd circle
			(at 15.200122 6.649974)
			(size 0.4572 0.4572)
			(layers "F.Cu" "F.Mask" "F.Paste")
			(net "Net_1679")
		)
		(pad "AM42" smd circle
			(at 16.150082 6.649974)
			(size 0.4572 0.4572)
			(layers "F.Cu" "F.Mask" "F.Paste")
			(net "Net_1691")
		)
		(pad "AM43" smd circle
			(at 17.100042 6.649974)
			(size 0.4572 0.4572)
			(layers "F.Cu" "F.Mask" "F.Paste")
			(net "GND")
		)
		(pad "AM44" smd circle
			(at 18.050002 6.649974)
			(size 0.4572 0.4572)
			(layers "F.Cu" "F.Mask" "F.Paste")
			(net "GND")
		)
		(pad "AM45" smd circle
			(at 18.999962 6.649974)
			(size 0.4572 0.4572)
			(layers "F.Cu" "F.Mask" "F.Paste")
			(net "GND")
		)
		(pad "AM46" smd circle
			(at 19.949922 6.649974)
			(size 0.4572 0.4572)
			(layers "F.Cu" "F.Mask" "F.Paste")
			(net "GND")
		)
		(pad "AM47" smd circle
			(at 20.899882 6.649974)
			(size 0.4572 0.4572)
			(layers "F.Cu" "F.Mask" "F.Paste")
			(net "GND")
		)
		(pad "AM48" smd circle
			(at 21.850096 6.649974)
			(size 0.4572 0.4572)
			(layers "F.Cu" "F.Mask" "F.Paste")
			(net "Net_1622")
		)
		(pad "AM49" smd circle
			(at 22.800056 6.649974)
			(size 0.4572 0.4572)
			(layers "F.Cu" "F.Mask" "F.Paste")
			(net "Net_1639")
		)
		(pad "AN1" smd circle
			(at -22.800056 7.599934)
			(size 0.4572 0.4572)
			(layers "F.Cu" "F.Mask" "F.Paste")
			(net "GND")
		)
		(pad "AN2" smd circle
			(at -21.850096 7.599934)
			(size 0.4572 0.4572)
			(layers "F.Cu" "F.Mask" "F.Paste")
			(net "GND")
		)
		(pad "AN3" smd circle
			(at -20.899882 7.599934)
			(size 0.4572 0.4572)
			(layers "F.Cu" "F.Mask" "F.Paste")
			(net "Net_1583")
		)
		(pad "AN4" smd circle
			(at -19.949922 7.599934)
			(size 0.4572 0.4572)
			(layers "F.Cu" "F.Mask" "F.Paste")
			(net "Net_1620")
		)
		(pad "AN5" smd circle
			(at -18.999962 7.599934)
			(size 0.4572 0.4572)
			(layers "F.Cu" "F.Mask" "F.Paste")
			(net "GND")
		)
		(pad "AN6" smd circle
			(at -18.050002 7.599934)
			(size 0.4572 0.4572)
			(layers "F.Cu" "F.Mask" "F.Paste")
			(net "Net_1448")
		)
		(pad "AN7" smd circle
			(at -17.100042 7.599934)
			(size 0.4572 0.4572)
			(layers "F.Cu" "F.Mask" "F.Paste")
			(net "Net_1383")
		)
		(pad "AN8" smd circle
			(at -16.150082 7.599934)
			(size 0.4572 0.4572)
			(layers "F.Cu" "F.Mask" "F.Paste")
			(net "GND")
		)
		(pad "AN9" smd circle
			(at -15.200122 7.599934)
			(size 0.4572 0.4572)
			(layers "F.Cu" "F.Mask" "F.Paste")
			(net "GND")
		)
		(pad "AN10" smd circle
			(at -14.249908 7.599934)
			(size 0.4572 0.4572)
			(layers "F.Cu" "F.Mask" "F.Paste")
			(net "GND")
		)
		(pad "AN11" smd circle
			(at -13.299948 7.599934)
			(size 0.4572 0.4572)
			(layers "F.Cu" "F.Mask" "F.Paste")
			(net "GND")
		)
		(pad "AN12" smd circle
			(at -12.349988 7.599934)
			(size 0.4572 0.4572)
			(layers "F.Cu" "F.Mask" "F.Paste")
			(net "GND")
		)
		(pad "AN13" smd circle
			(at -11.400028 7.599934)
			(size 0.4572 0.4572)
			(layers "F.Cu" "F.Mask" "F.Paste")
			(net "GND")
		)
		(pad "AN14" smd circle
			(at -10.450068 7.599934)
			(size 0.4572 0.4572)
			(layers "F.Cu" "F.Mask" "F.Paste")
			(net "Net_519")
		)
		(pad "AN15" smd circle
			(at -9.500108 7.599934)
			(size 0.4572 0.4572)
			(layers "F.Cu" "F.Mask" "F.Paste")
			(net "GND")
		)
		(pad "AN16" smd circle
			(at -8.549894 7.599934)
			(size 0.4572 0.4572)
			(layers "F.Cu" "F.Mask" "F.Paste")
			(net "GND")
		)
		(pad "AN17" smd circle
			(at -7.599934 7.599934)
			(size 0.4572 0.4572)
			(layers "F.Cu" "F.Mask" "F.Paste")
			(net "GND")
		)
		(pad "AN18" smd circle
			(at -6.649974 7.599934)
			(size 0.4572 0.4572)
			(layers "F.Cu" "F.Mask" "F.Paste")
			(net "GND")
		)
		(pad "AN19" smd circle
			(at -5.700014 7.599934)
			(size 0.4572 0.4572)
			(layers "F.Cu" "F.Mask" "F.Paste")
			(net "GND")
		)
		(pad "AN20" smd circle
			(at -4.750054 7.599934)
			(size 0.4572 0.4572)
			(layers "F.Cu" "F.Mask" "F.Paste")
			(net "GND")
		)
		(pad "AN21" smd circle
			(at -3.800094 7.599934)
			(size 0.4572 0.4572)
			(layers "F.Cu" "F.Mask" "F.Paste")
			(net "GND")
		)
		(pad "AN22" smd circle
			(at -2.84988 7.599934)
			(size 0.4572 0.4572)
			(layers "F.Cu" "F.Mask" "F.Paste")
			(net "GND")
		)
		(pad "AN23" smd circle
			(at -1.89992 7.599934)
			(size 0.4572 0.4572)
			(layers "F.Cu" "F.Mask" "F.Paste")
			(net "GND")
		)
		(pad "AN24" smd circle
			(at -0.94996 7.599934)
			(size 0.4572 0.4572)
			(layers "F.Cu" "F.Mask" "F.Paste")
			(net "GND")
		)
		(pad "AN25" smd circle
			(at 0 7.599934)
			(size 0.4572 0.4572)
			(layers "F.Cu" "F.Mask" "F.Paste")
			(net "GND")
		)
		(pad "AN26" smd circle
			(at 0.94996 7.599934)
			(size 0.4572 0.4572)
			(layers "F.Cu" "F.Mask" "F.Paste")
			(net "GND")
		)
		(pad "AN27" smd circle
			(at 1.89992 7.599934)
			(size 0.4572 0.4572)
			(layers "F.Cu" "F.Mask" "F.Paste")
			(net "GND")
		)
		(pad "AN28" smd circle
			(at 2.84988 7.599934)
			(size 0.4572 0.4572)
			(layers "F.Cu" "F.Mask" "F.Paste")
			(net "GND")
		)
		(pad "AN29" smd circle
			(at 3.800094 7.599934)
			(size 0.4572 0.4572)
			(layers "F.Cu" "F.Mask" "F.Paste")
			(net "GND")
		)
		(pad "AN30" smd circle
			(at 4.750054 7.599934)
			(size 0.4572 0.4572)
			(layers "F.Cu" "F.Mask" "F.Paste")
			(net "GND")
		)
		(pad "AN31" smd circle
			(at 5.700014 7.599934)
			(size 0.4572 0.4572)
			(layers "F.Cu" "F.Mask" "F.Paste")
			(net "GND")
		)
		(pad "AN32" smd circle
			(at 6.649974 7.599934)
			(size 0.4572 0.4572)
			(layers "F.Cu" "F.Mask" "F.Paste")
			(net "GND")
		)
		(pad "AN33" smd circle
			(at 7.599934 7.599934)
			(size 0.4572 0.4572)
			(layers "F.Cu" "F.Mask" "F.Paste")
			(net "GND")
		)
		(pad "AN34" smd circle
			(at 8.549894 7.599934)
			(size 0.4572 0.4572)
			(layers "F.Cu" "F.Mask" "F.Paste")
			(net "GND")
		)
		(pad "AN35" smd circle
			(at 9.500108 7.599934)
			(size 0.4572 0.4572)
			(layers "F.Cu" "F.Mask" "F.Paste")
			(net "GND")
		)
		(pad "AN36" smd circle
			(at 10.450068 7.599934)
			(size 0.4572 0.4572)
			(layers "F.Cu" "F.Mask" "F.Paste")
			(net "Net_518")
		)
		(pad "AN37" smd circle
			(at 11.400028 7.599934)
			(size 0.4572 0.4572)
			(layers "F.Cu" "F.Mask" "F.Paste")
			(net "GND")
		)
		(pad "AN38" smd circle
			(at 12.349988 7.599934)
			(size 0.4572 0.4572)
			(layers "F.Cu" "F.Mask" "F.Paste")
			(net "Net_5360")
		)
		(pad "AN39" smd circle
			(at 13.299948 7.599934)
			(size 0.4572 0.4572)
			(layers "F.Cu" "F.Mask" "F.Paste")
			(net "Net_5327")
		)
		(pad "AN40" smd circle
			(at 14.249908 7.599934)
			(size 0.4572 0.4572)
			(layers "F.Cu" "F.Mask" "F.Paste")
			(net "GND")
		)
		(pad "AN41" smd circle
			(at 15.200122 7.599934)
			(size 0.4572 0.4572)
			(layers "F.Cu" "F.Mask" "F.Paste")
			(net "GND")
		)
		(pad "AN42" smd circle
			(at 16.150082 7.599934)
			(size 0.4572 0.4572)
			(layers "F.Cu" "F.Mask" "F.Paste")
			(net "GND")
		)
		(pad "AN43" smd circle
			(at 17.100042 7.599934)
			(size 0.4572 0.4572)
			(layers "F.Cu" "F.Mask" "F.Paste")
			(net "P5E_PEX2_STN0_TX_DP<0>")
		)
		(pad "AN44" smd circle
			(at 18.050002 7.599934)
			(size 0.4572 0.4572)
			(layers "F.Cu" "F.Mask" "F.Paste")
			(net "P5E_PEX2_STN0_TX_DN<0>")
		)
		(pad "AN45" smd circle
			(at 18.999962 7.599934)
			(size 0.4572 0.4572)
			(layers "F.Cu" "F.Mask" "F.Paste")
			(net "GND")
		)
		(pad "AN46" smd circle
			(at 19.949922 7.599934)
			(size 0.4572 0.4572)
			(layers "F.Cu" "F.Mask" "F.Paste")
			(net "P5E_PEX2_STN0_RX_DP<0>")
		)
		(pad "AN47" smd circle
			(at 20.899882 7.599934)
			(size 0.4572 0.4572)
			(layers "F.Cu" "F.Mask" "F.Paste")
			(net "P5E_PEX2_STN0_RX_DN<0>")
		)
		(pad "AN48" smd circle
			(at 21.850096 7.599934)
			(size 0.4572 0.4572)
			(layers "F.Cu" "F.Mask" "F.Paste")
			(net "GND")
		)
		(pad "AN49" smd circle
			(at 22.800056 7.599934)
			(size 0.4572 0.4572)
			(layers "F.Cu" "F.Mask" "F.Paste")
			(net "GND")
		)
		(pad "AP1" smd circle
			(at -22.800056 8.549894)
			(size 0.4572 0.4572)
			(layers "F.Cu" "F.Mask" "F.Paste")
			(net "Net_1598")
		)
		(pad "AP2" smd circle
			(at -21.850096 8.549894)
			(size 0.4572 0.4572)
			(layers "F.Cu" "F.Mask" "F.Paste")
			(net "Net_1593")
		)
		(pad "AP3" smd circle
			(at -20.899882 8.549894)
			(size 0.4572 0.4572)
			(layers "F.Cu" "F.Mask" "F.Paste")
			(net "GND")
		)
		(pad "AP4" smd circle
			(at -19.949922 8.549894)
			(size 0.4572 0.4572)
			(layers "F.Cu" "F.Mask" "F.Paste")
			(net "GND")
		)
		(pad "AP5" smd circle
			(at -18.999962 8.549894)
			(size 0.4572 0.4572)
			(layers "F.Cu" "F.Mask" "F.Paste")
			(net "GND")
		)
		(pad "AP6" smd circle
			(at -18.050002 8.549894)
			(size 0.4572 0.4572)
			(layers "F.Cu" "F.Mask" "F.Paste")
			(net "GND")
		)
		(pad "AP7" smd circle
			(at -17.100042 8.549894)
			(size 0.4572 0.4572)
			(layers "F.Cu" "F.Mask" "F.Paste")
			(net "GND")
		)
		(pad "AP8" smd circle
			(at -16.150082 8.549894)
			(size 0.4572 0.4572)
			(layers "F.Cu" "F.Mask" "F.Paste")
			(net "Net_1371")
		)
		(pad "AP9" smd circle
			(at -15.200122 8.549894)
			(size 0.4572 0.4572)
			(layers "F.Cu" "F.Mask" "F.Paste")
			(net "Net_1420")
		)
		(pad "AP10" smd circle
			(at -14.249908 8.549894)
			(size 0.4572 0.4572)
			(layers "F.Cu" "F.Mask" "F.Paste")
			(net "GND")
		)
		(pad "AP11" smd circle
			(at -13.299948 8.549894)
			(size 0.4572 0.4572)
			(layers "F.Cu" "F.Mask" "F.Paste")
			(net "GND")
		)
		(pad "AP12" smd circle
			(at -12.349988 8.549894)
			(size 0.4572 0.4572)
			(layers "F.Cu" "F.Mask" "F.Paste")
			(net "GND")
		)
		(pad "AP13" smd circle
			(at -11.400028 8.549894)
			(size 0.4572 0.4572)
			(layers "F.Cu" "F.Mask" "F.Paste")
			(net "GND")
		)
		(pad "AP14" smd circle
			(at -10.450068 8.549894)
			(size 0.4572 0.4572)
			(layers "F.Cu" "F.Mask" "F.Paste")
			(net "Net_521")
		)
		(pad "AP15" smd circle
			(at -9.500108 8.549894)
			(size 0.4572 0.4572)
			(layers "F.Cu" "F.Mask" "F.Paste")
			(net "GND")
		)
		(pad "AP16" smd circle
			(at -8.549894 8.549894)
			(size 0.4572 0.4572)
			(layers "F.Cu" "F.Mask" "F.Paste")
			(net "P1V25_SERDES_VDDPLL_PEX2")
		)
		(pad "AP17" smd circle
			(at -7.599934 8.549894)
			(size 0.4572 0.4572)
			(layers "F.Cu" "F.Mask" "F.Paste")
			(net "P1V25_SERDES_VDDPLL_PEX2")
		)
		(pad "AP18" smd circle
			(at -6.649974 8.549894)
			(size 0.4572 0.4572)
			(layers "F.Cu" "F.Mask" "F.Paste")
			(net "P1V25_SERDES_VDDPLL_PEX2")
		)
		(pad "AP19" smd circle
			(at -5.700014 8.549894)
			(size 0.4572 0.4572)
			(layers "F.Cu" "F.Mask" "F.Paste")
			(net "P1V25_SERDES_VDDPLL_PEX2")
		)
		(pad "AP20" smd circle
			(at -4.750054 8.549894)
			(size 0.4572 0.4572)
			(layers "F.Cu" "F.Mask" "F.Paste")
			(net "P1V25_SERDES_VDDPLL_PEX2")
		)
		(pad "AP21" smd circle
			(at -3.800094 8.549894)
			(size 0.4572 0.4572)
			(layers "F.Cu" "F.Mask" "F.Paste")
			(net "P1V25_SERDES_VDDPLL_PEX2")
		)
		(pad "AP22" smd circle
			(at -2.84988 8.549894)
			(size 0.4572 0.4572)
			(layers "F.Cu" "F.Mask" "F.Paste")
			(net "P1V25_SERDES_VDDPLL_PEX2")
		)
		(pad "AP23" smd circle
			(at -1.89992 8.549894)
			(size 0.4572 0.4572)
			(layers "F.Cu" "F.Mask" "F.Paste")
			(net "P1V25_SERDES_VDDPLL_PEX2")
		)
		(pad "AP24" smd circle
			(at -0.94996 8.549894)
			(size 0.4572 0.4572)
			(layers "F.Cu" "F.Mask" "F.Paste")
			(net "P1V25_SERDES_VDDPLL_PEX2")
		)
		(pad "AP25" smd circle
			(at 0 8.549894)
			(size 0.4572 0.4572)
			(layers "F.Cu" "F.Mask" "F.Paste")
			(net "P1V25_SERDES_VDDPLL_PEX2")
		)
		(pad "AP26" smd circle
			(at 0.94996 8.549894)
			(size 0.4572 0.4572)
			(layers "F.Cu" "F.Mask" "F.Paste")
			(net "P1V25_SERDES_VDDPLL_PEX2")
		)
		(pad "AP27" smd circle
			(at 1.89992 8.549894)
			(size 0.4572 0.4572)
			(layers "F.Cu" "F.Mask" "F.Paste")
			(net "P1V25_SERDES_VDDPLL_PEX2")
		)
		(pad "AP28" smd circle
			(at 2.84988 8.549894)
			(size 0.4572 0.4572)
			(layers "F.Cu" "F.Mask" "F.Paste")
			(net "P1V25_SERDES_VDDPLL_PEX2")
		)
		(pad "AP29" smd circle
			(at 3.800094 8.549894)
			(size 0.4572 0.4572)
			(layers "F.Cu" "F.Mask" "F.Paste")
			(net "P1V25_SERDES_VDDPLL_PEX2")
		)
	)
)
